# T6G (Grand Teton) — schematic netlist excerpt (pin names and nets, part order shuffled) for the footprints in the layout excerpt that follows; sources: Cadence DE-HDL packaged netlist, KiCad conversion of 04192023_DAF0TMB3IC0_F0TG_MB_C_brd_V02_OCP.brd

R470  Q_RES  33 5% CHIP  pkg 0402LF  page 29 : A = ESPI_CPU0_D2 ; B = ESPI_CPU0_R_D2
PR2521  Q_RES  1 1% CHIP  pkg 0402LF  page 266 : A = P12V_HSC_SENSE2_P ; B = P12V_HSC_SENSE2_R2_P

(kicad_pcb
	(version 20260206)
	(generator "pcbnew")
	(generator_version "10.0")
	(general
		(thickness 1.6)
		(legacy_teardrops no)
	)
	(paper "A4")
	(title_block
		(title "04192023_DAF0TMB3IC0_F0TG_MB_C_brd_V02_OCP.brd")
		(comment 1 "Grand Teton / footprints 5249-5250 of 8354")
	)
	(layers
		(0 "F.Cu" signal "TOP")
		(4 "In1.Cu" signal "GND")
		(6 "In2.Cu" signal "IN1")
		(8 "In3.Cu" signal "GND1")
		(10 "In4.Cu" signal "IN2")
		(12 "In5.Cu" signal "GND2")
		(14 "In6.Cu" signal "IN3")
		(16 "In7.Cu" signal "GND3")
		(18 "In8.Cu" signal "VCC")
		(20 "In9.Cu" signal "VCC1")
		(22 "In10.Cu" signal "GND4")
		(24 "In11.Cu" signal "IN4")
		(26 "In12.Cu" signal "GND5")
		(28 "In13.Cu" signal "IN5")
		(30 "In14.Cu" signal "GND6")
		(32 "In15.Cu" signal "IN6")
		(34 "In16.Cu" signal "GND7")
		(2 "B.Cu" signal "BOTTOM")
		(9 "F.Adhes" user "F.Adhesive")
		(11 "B.Adhes" user "B.Adhesive")
		(13 "F.Paste" user "Package Geometry/Pastemask Top")
		(15 "B.Paste" user "Package Geometry/Pastemask Bottom")
		(5 "F.SilkS" user "Ref Des/Silkscreen Top")
		(7 "B.SilkS" user "Ref Des/Silkscreen Bottom")
		(1 "F.Mask" user "Board Geometry/Soldermask Top")
		(3 "B.Mask" user "Board Geometry/Soldermask Bottom")
		(17 "Dwgs.User" user "User.Drawings")
		(19 "Cmts.User" user "User.Comments")
		(21 "Eco1.User" user "User.Eco1")
		(23 "Eco2.User" user "User.Eco2")
		(25 "Edge.Cuts" user "Board Geometry/Outline")
		(27 "Margin" user)
		(31 "F.CrtYd" user "Package Geometry/Place Bound Top")
		(29 "B.CrtYd" user "Package Geometry/Place Bound Bottom")
		(35 "F.Fab" user "Ref Des/Assembly Top")
		(33 "B.Fab" user "Ref Des/Assembly Bottom")
	)
	(footprint ""
		(layer "B.Cu")
		(at 206.429356 -385.136136 180)
		(property "Reference" "PR2521"
			(at 0 0 0)
			(layer "B.SilkS")
			(hide yes)
			(effects
				(font
					(size 1.27 1.27)
				)
				(justify mirror)
			)
		)
		(property "Value" ""
			(at 0 0 0)
			(layer "B.Fab")
			(effects
				(font
					(size 1.27 1.27)
				)
				(justify mirror)
			)
		)
		(duplicate_pad_numbers_are_jumpers no)
		(fp_line
			(start 0.7874 0.4064)
			(end 0.7874 -0.4064)
			(stroke
				(width 0.1524)
				(type default)
			)
			(layer "B.SilkS")
		)
		(fp_line
			(start 0.7874 -0.4064)
			(end -0.7874 -0.4064)
			(stroke
				(width 0.1524)
				(type default)
			)
			(layer "B.SilkS")
		)
		(fp_line
			(start -0.7874 0.4064)
			(end 0.7874 0.4064)
			(stroke
				(width 0.1524)
				(type default)
			)
			(layer "B.SilkS")
		)
		(fp_line
			(start -0.7874 -0.4064)
			(end -0.7874 0.4064)
			(stroke
				(width 0.1524)
				(type default)
			)
			(layer "B.SilkS")
		)
		(fp_line
			(start 0.67945 0.3048)
			(end 0.67945 -0.305054)
			(stroke
				(width 0.1)
				(type default)
			)
			(layer "B.Fab")
		)
		(fp_line
			(start 0.67945 -0.305054)
			(end 0.12065 -0.305054)
			(stroke
				(width 0.1)
				(type default)
			)
			(layer "B.Fab")
		)
		(fp_line
			(start 0.12065 0.3048)
			(end 0.67945 0.3048)
			(stroke
				(width 0.1)
				(type default)
			)
			(layer "B.Fab")
		)
		(fp_line
			(start 0.12065 0.2794)
			(end 0.12065 0.3048)
			(stroke
				(width 0.1)
				(type default)
			)
			(layer "B.Fab")
		)
		(fp_line
			(start 0.12065 -0.2794)
			(end -0.12065 -0.2794)
			(stroke
				(width 0.1)
				(type default)
			)
			(layer "B.Fab")
		)
		(fp_line
			(start 0.12065 -0.305054)
			(end 0.12065 -0.2794)
			(stroke
				(width 0.1)
				(type default)
			)
			(layer "B.Fab")
		)
		(fp_line
			(start -0.120396 0.3048)
			(end -0.120396 0.2794)
			(stroke
				(width 0.1)
				(type default)
			)
			(layer "B.Fab")
		)
		(fp_line
			(start -0.120396 0.2794)
			(end 0.12065 0.2794)
			(stroke
				(width 0.1)
				(type default)
			)
			(layer "B.Fab")
		)
		(fp_line
			(start -0.12065 -0.2794)
			(end -0.12065 -0.3048)
			(stroke
				(width 0.1)
				(type default)
			)
			(layer "B.Fab")
		)
		(fp_line
			(start -0.12065 -0.3048)
			(end -0.67945 -0.3048)
			(stroke
				(width 0.1)
				(type default)
			)
			(layer "B.Fab")
		)
		(fp_line
			(start -0.67945 0.3048)
			(end -0.120396 0.3048)
			(stroke
				(width 0.1)
				(type default)
			)
			(layer "B.Fab")
		)
		(fp_line
			(start -0.67945 -0.3048)
			(end -0.67945 0.3048)
			(stroke
				(width 0.1)
				(type default)
			)
			(layer "B.Fab")
		)
		(pad "1" smd circle
			(at 0.40005 0)
			(size 0 0)
			(layers "B.Cu" "B.Mask" "B.Paste")
			(net "P12V_HSC_SENSE2_P")
		)
		(pad "2" smd circle
			(at -0.40005 0)
			(size 0 0)
			(layers "B.Cu" "B.Mask" "B.Paste")
			(net "P12V_HSC_SENSE2_R2_P")
		)
	)
	(footprint ""
		(layer "B.Cu")
		(at 393.617958 -324.862952)
		(property "Reference" "R470"
			(at 0 0 0)
			(layer "B.SilkS")
			(hide yes)
			(effects
				(font
					(size 1.27 1.27)
				)
				(justify mirror)
			)
		)
		(property "Value" ""
			(at 0 0 0)
			(layer "B.Fab")
			(effects
				(font
					(size 1.27 1.27)
				)
				(justify mirror)
			)
		)
		(duplicate_pad_numbers_are_jumpers no)
		(fp_line
			(start -0.7874 -0.4064)
			(end -0.7874 0.4064)
			(stroke
				(width 0.1524)
				(type default)
			)
			(layer "B.SilkS")
		)
		(fp_line
			(start -0.7874 0.4064)
			(end 0.7874 0.4064)
			(stroke
				(width 0.1524)
				(type default)
			)
			(layer "B.SilkS")
		)
		(fp_line
			(start 0.7874 -0.4064)
			(end -0.7874 -0.4064)
			(stroke
				(width 0.1524)
				(type default)
			)
			(layer "B.SilkS")
		)
		(fp_line
			(start 0.7874 0.4064)
			(end 0.7874 -0.4064)
			(stroke
				(width 0.1524)
				(type default)
			)
			(layer "B.SilkS")
		)
		(fp_line
			(start -0.67945 -0.3048)
			(end -0.67945 0.3048)
			(stroke
				(width 0.1)
				(type default)
			)
			(layer "B.Fab")
		)
		(fp_line
			(start -0.67945 0.3048)
			(end -0.120396 0.3048)
			(stroke
				(width 0.1)
				(type default)
			)
			(layer "B.Fab")
		)
		(fp_line
			(start -0.12065 -0.3048)
			(end -0.67945 -0.3048)
			(stroke
				(width 0.1)
				(type default)
			)
			(layer "B.Fab")
		)
		(fp_line
			(start -0.12065 -0.2794)
			(end -0.12065 -0.3048)
			(stroke
				(width 0.1)
				(type default)
			)
			(layer "B.Fab")
		)
		(fp_line
			(start -0.120396 0.2794)
			(end 0.12065 0.2794)
			(stroke
				(width 0.1)
				(type default)
			)
			(layer "B.Fab")
		)
		(fp_line
			(start -0.120396 0.3048)
			(end -0.120396 0.2794)
			(stroke
				(width 0.1)
				(type default)
			)
			(layer "B.Fab")
		)
		(fp_line
			(start 0.12065 -0.305054)
			(end 0.12065 -0.2794)
			(stroke
				(width 0.1)
				(type default)
			)
			(layer "B.Fab")
		)
		(fp_line
			(start 0.12065 -0.2794)
			(end -0.12065 -0.2794)
			(stroke
				(width 0.1)
				(type default)
			)
			(layer "B.Fab")
		)
		(fp_line
			(start 0.12065 0.2794)
			(end 0.12065 0.3048)
			(stroke
				(width 0.1)
				(type default)
			)
			(layer "B.Fab")
		)
		(fp_line
			(start 0.12065 0.3048)
			(end 0.67945 0.3048)
			(stroke
				(width 0.1)
				(type default)
			)
			(layer "B.Fab")
		)
		(fp_line
			(start 0.67945 -0.305054)
			(end 0.12065 -0.305054)
			(stroke
				(width 0.1)
				(type default)
			)
			(layer "B.Fab")
		)
		(fp_line
			(start 0.67945 0.3048)
			(end 0.67945 -0.305054)
			(stroke
				(width 0.1)
				(type default)
			)
			(layer "B.Fab")
		)
		(pad "1" smd circle
			(at 0.40005 0 180)
			(size 0 0)
			(layers "B.Cu" "B.Mask" "B.Paste")
			(net "ESPI_CPU0_D2")
		)
		(pad "2" smd circle
			(at -0.40005 0 180)
			(size 0 0)
			(layers "B.Cu" "B.Mask" "B.Paste")
			(net "ESPI_CPU0_R_D2")
		)
	)
)
